(kicad_pcb
	(version 20260206)
	(generator "pcbnew")
	(generator_version "10.0")
	(general
		(thickness 1.6)
		(legacy_teardrops no)
	)
	(paper "A4")
	(title_block
		(title "pdpb — Lightning_PDPB_BRD.brd")
		(comment 1 "Lightning (Wiwynn / Facebook NVMe JBOF) / footprints 500-503 of 1140")
	)
	(layers
		(0 "F.Cu" signal "TOP")
		(4 "In1.Cu" signal "L2GND")
		(6 "In2.Cu" signal "L3")
		(8 "In3.Cu" signal "L4VCC")
		(10 "In4.Cu" signal "L5VCC")
		(12 "In5.Cu" signal "L6")
		(14 "In6.Cu" signal "L7GND")
		(2 "B.Cu" signal "BOTTOM")
		(9 "F.Adhes" user "F.Adhesive")
		(11 "B.Adhes" user "B.Adhesive")
		(13 "F.Paste" user "Package Geometry/Pastemask Top")
		(15 "B.Paste" user "Package Geometry/Pastemask Bottom")
		(5 "F.SilkS" user "Ref Des/Silkscreen Top")
		(7 "B.SilkS" user "Ref Des/Silkscreen Bottom")
		(1 "F.Mask" user "Board Geometry/Soldermask Top")
		(3 "B.Mask" user "Board Geometry/Soldermask Bottom")
		(17 "Dwgs.User" user "User.Drawings")
		(19 "Cmts.User" user "User.Comments")
		(21 "Eco1.User" user "User.Eco1")
		(23 "Eco2.User" user "User.Eco2")
		(25 "Edge.Cuts" user "Board Geometry/Outline")
		(27 "Margin" user)
		(31 "F.CrtYd" user "Package Geometry/Place Bound Top")
		(29 "B.CrtYd" user "Package Geometry/Place Bound Bottom")
		(35 "F.Fab" user "Ref Des/Assembly Top")
		(33 "B.Fab" user "Ref Des/Assembly Bottom")
	)
	(footprint ""
		(layer "F.Cu")
		(at 228.219 -439.166)
		(property "Reference" "PR96"
			(at 0 0 0)
			(layer "F.SilkS")
			(hide yes)
			(effects
				(font
					(size 1.27 1.27)
				)
			)
		)
		(property "Value" "37K4R2F-1-GP"
			(at 0.064008 -3.993896 0)
			(unlocked yes)
			(layer "F.Fab")
			(hide yes)
			(effects
				(font
					(size 1.016 1.016)
					(thickness 0.1524)
				)
			)
		)
		(property "Device Type" "R402H16"
			(at 0.064008 -5.517896 0)
			(unlocked yes)
			(layer "F.Fab")
			(hide yes)
			(effects
				(font
					(size 1.016 1.016)
					(thickness 0.1524)
				)
			)
		)
		(duplicate_pad_numbers_are_jumpers no)
		(fp_line
			(start -0.508 -0.9398)
			(end -0.508 0.9398)
			(stroke
				(width 0.1524)
				(type default)
			)
			(layer "F.SilkS")
		)
		(fp_line
			(start 0.508 -0.9398)
			(end -0.508 -0.9398)
			(stroke
				(width 0.1524)
				(type default)
			)
			(layer "F.SilkS")
		)
		(fp_rect
			(start -0.508 0.9398)
			(end 0.508 -0.9398)
			(stroke
				(width 0)
				(type default)
			)
			(fill no)
			(layer "F.CrtYd")
		)
		(fp_rect
			(start -0.508 0.9398)
			(end 0.508 -0.9398)
			(stroke
				(width 0)
				(type default)
			)
			(fill no)
			(layer "F.Fab")
		)
		(pad "1" smd custom
			(at 0 -0.4445)
			(size 0.1397 0.1397)
			(layers "F.Cu" "F.Mask" "F.Paste")
			(net "P12V")
			(options
				(clearance outline)
				(anchor circle)
			)
			(primitives
				(gr_poly
					(pts
						(arc
							(start -0.1778 -0.2794)
							(mid -0.249642 -0.249642)
							(end -0.2794 -0.1778)
						)
						(arc
							(start -0.2794 0.1778)
							(mid -0.249642 0.249642)
							(end -0.1778 0.2794)
						)
						(arc
							(start 0.1778 0.2794)
							(mid 0.249642 0.249642)
							(end 0.2794 0.1778)
						)
						(arc
							(start 0.2794 -0.1778)
							(mid 0.249642 -0.249642)
							(end 0.1778 -0.2794)
						)
					)
					(width 0)
					(fill yes)
				)
			)
		)
		(pad "2" smd custom
			(at 0 0.4445)
			(size 0.1397 0.1397)
			(layers "F.Cu" "F.Mask" "F.Paste")
			(net "P3V3_EN_R")
			(options
				(clearance outline)
				(anchor circle)
			)
			(primitives
				(gr_poly
					(pts
						(arc
							(start -0.1778 -0.2794)
							(mid -0.249642 -0.249642)
							(end -0.2794 -0.1778)
						)
						(arc
							(start -0.2794 0.1778)
							(mid -0.249642 0.249642)
							(end -0.1778 0.2794)
						)
						(arc
							(start 0.1778 0.2794)
							(mid 0.249642 0.249642)
							(end 0.2794 0.1778)
						)
						(arc
							(start 0.2794 -0.1778)
							(mid 0.249642 -0.249642)
							(end 0.1778 -0.2794)
						)
					)
					(width 0)
					(fill yes)
				)
			)
		)
	)
	(footprint ""
		(layer "F.Cu")
		(at 78.3844 -209.3722 180)
		(property "Reference" "R9967"
			(at 0 0 180)
			(layer "F.SilkS")
			(hide yes)
			(effects
				(font
					(size 1.27 1.27)
				)
			)
		)
		(property "Value" "470R2F-GP"
			(at 0.064008 -3.993896 180)
			(unlocked yes)
			(layer "F.Fab")
			(hide yes)
			(effects
				(font
					(size 1.016 1.016)
					(thickness 0.1524)
				)
			)
		)
		(property "Device Type" "R402H16"
			(at 0.064008 -5.517896 180)
			(unlocked yes)
			(layer "F.Fab")
			(hide yes)
			(effects
				(font
					(size 1.016 1.016)
					(thickness 0.1524)
				)
			)
		)
		(duplicate_pad_numbers_are_jumpers no)
		(fp_line
			(start 0.508 -0.9398)
			(end -0.508 -0.9398)
			(stroke
				(width 0.1524)
				(type default)
			)
			(layer "F.SilkS")
		)
		(fp_line
			(start -0.508 -0.9398)
			(end -0.508 0.9398)
			(stroke
				(width 0.1524)
				(type default)
			)
			(layer "F.SilkS")
		)
		(fp_rect
			(start -0.508 0.9398)
			(end 0.508 -0.9398)
			(stroke
				(width 0)
				(type default)
			)
			(fill no)
			(layer "F.CrtYd")
		)
		(fp_rect
			(start -0.508 0.9398)
			(end 0.508 -0.9398)
			(stroke
				(width 0)
				(type default)
			)
			(fill no)
			(layer "F.Fab")
		)
		(pad "1" smd custom
			(at 0 -0.4445 180)
			(size 0.1397 0.1397)
			(layers "F.Cu" "F.Mask" "F.Paste")
			(net "VDD_DIFF_3")
			(options
				(clearance outline)
				(anchor circle)
			)
			(primitives
				(gr_poly
					(pts
						(arc
							(start -0.1778 -0.2794)
							(mid -0.249642 -0.249642)
							(end -0.2794 -0.1778)
						)
						(arc
							(start -0.2794 0.1778)
							(mid -0.249642 0.249642)
							(end -0.1778 0.2794)
						)
						(arc
							(start 0.1778 0.2794)
							(mid 0.249642 0.249642)
							(end 0.2794 0.1778)
						)
						(arc
							(start 0.2794 -0.1778)
							(mid 0.249642 -0.249642)
							(end 0.1778 -0.2794)
						)
					)
					(width 0)
					(fill yes)
				)
			)
		)
		(pad "2" smd custom
			(at 0 0.4445 180)
			(size 0.1397 0.1397)
			(layers "F.Cu" "F.Mask" "F.Paste")
			(net "PE_100M_CLK2_N")
			(options
				(clearance outline)
				(anchor circle)
			)
			(primitives
				(gr_poly
					(pts
						(arc
							(start -0.1778 -0.2794)
							(mid -0.249642 -0.249642)
							(end -0.2794 -0.1778)
						)
						(arc
							(start -0.2794 0.1778)
							(mid -0.249642 0.249642)
							(end -0.1778 0.2794)
						)
						(arc
							(start 0.1778 0.2794)
							(mid 0.249642 0.249642)
							(end 0.2794 0.1778)
						)
						(arc
							(start 0.2794 -0.1778)
							(mid 0.249642 -0.249642)
							(end 0.1778 -0.2794)
						)
					)
					(width 0)
					(fill yes)
				)
			)
		)
	)
	(footprint ""
		(layer "F.Cu")
		(at 210.312 -396.113)
		(property "Reference" "C383"
			(at 0 0 0)
			(layer "F.SilkS")
			(hide yes)
			(effects
				(font
					(size 1.27 1.27)
				)
			)
		)
		(property "Value" "SCD1U25V2KX-2-GP"
			(at 1.1811 -2.7051 0)
			(unlocked yes)
			(layer "F.Fab")
			(hide yes)
			(effects
				(font
					(size 1.016 1.016)
					(thickness 0.1524)
				)
			)
		)
		(property "Device Type" "C402H22"
			(at 1.1811 -4.2291 0)
			(unlocked yes)
			(layer "F.Fab")
			(hide yes)
			(effects
				(font
					(size 1.016 1.016)
					(thickness 0.1524)
				)
			)
		)
		(duplicate_pad_numbers_are_jumpers no)
		(fp_rect
			(start -0.4318 0.9525)
			(end 0.4318 -0.9525)
			(stroke
				(width 0)
				(type default)
			)
			(fill no)
			(layer "F.CrtYd")
		)
		(fp_rect
			(start -0.4318 0.9525)
			(end 0.4318 -0.9525)
			(stroke
				(width 0)
				(type default)
			)
			(fill no)
			(layer "F.Fab")
		)
		(pad "1" smd custom
			(at 0 -0.4445)
			(size 0.1524 0.1524)
			(layers "F.Cu" "F.Mask" "F.Paste")
			(net "P12V")
			(options
				(clearance outline)
				(anchor circle)
			)
			(primitives
				(gr_poly
					(pts
						(arc
							(start 0.3048 -0.2032)
							(mid 0.275042 -0.275042)
							(end 0.2032 -0.3048)
						)
						(arc
							(start -0.2032 -0.3048)
							(mid -0.275042 -0.275042)
							(end -0.3048 -0.2032)
						)
						(arc
							(start -0.3048 0.2032)
							(mid -0.275042 0.275042)
							(end -0.2032 0.3048)
						)
						(arc
							(start 0.2032 0.3048)
							(mid 0.275042 0.275042)
							(end 0.3048 0.2032)
						)
					)
					(width 0)
					(fill yes)
				)
			)
		)
		(pad "2" smd custom
			(at 0 0.4445)
			(size 0.1524 0.1524)
			(layers "F.Cu" "F.Mask" "F.Paste")
			(net "SW_SSD1_N")
			(options
				(clearance outline)
				(anchor circle)
			)
			(primitives
				(gr_poly
					(pts
						(arc
							(start 0.3048 -0.2032)
							(mid 0.275042 -0.275042)
							(end 0.2032 -0.3048)
						)
						(arc
							(start -0.2032 -0.3048)
							(mid -0.275042 -0.275042)
							(end -0.3048 -0.2032)
						)
						(arc
							(start -0.3048 0.2032)
							(mid -0.275042 0.275042)
							(end -0.2032 0.3048)
						)
						(arc
							(start 0.2032 0.3048)
							(mid 0.275042 0.275042)
							(end 0.3048 0.2032)
						)
					)
					(width 0)
					(fill yes)
				)
			)
		)
	)
	(footprint ""
		(layer "F.Cu")
		(at 212.471 -44.704)
		(property "Reference" "R336"
			(at 0 0 0)
			(layer "F.SilkS")
			(hide yes)
			(effects
				(font
					(size 1.27 1.27)
				)
			)
		)
		(property "Value" "4K7R2J-2-GP"
			(at 0.064008 -3.993896 0)
			(unlocked yes)
			(layer "F.Fab")
			(hide yes)
			(effects
				(font
					(size 1.016 1.016)
					(thickness 0.1524)
				)
			)
		)
		(property "Device Type" "R402H16"
			(at 0.064008 -5.517896 0)
			(unlocked yes)
			(layer "F.Fab")
			(hide yes)
			(effects
				(font
					(size 1.016 1.016)
					(thickness 0.1524)
				)
			)
		)
		(duplicate_pad_numbers_are_jumpers no)
		(fp_line
			(start -0.508 -0.9398)
			(end -0.508 0.9398)
			(stroke
				(width 0.1524)
				(type default)
			)
			(layer "F.SilkS")
		)
		(fp_line
			(start 0.508 -0.9398)
			(end -0.508 -0.9398)
			(stroke
				(width 0.1524)
				(type default)
			)
			(layer "F.SilkS")
		)
		(fp_rect
			(start -0.508 0.9398)
			(end 0.508 -0.9398)
			(stroke
				(width 0)
				(type default)
			)
			(fill no)
			(layer "F.CrtYd")
		)
		(fp_rect
			(start -0.508 0.9398)
			(end 0.508 -0.9398)
			(stroke
				(width 0)
				(type default)
			)
			(fill no)
			(layer "F.Fab")
		)
		(pad "1" smd custom
			(at 0 -0.4445)
			(size 0.1397 0.1397)
			(layers "F.Cu" "F.Mask" "F.Paste")
			(net "I2C_B_TMP3_A2")
			(options
				(clearance outline)
				(anchor circle)
			)
			(primitives
				(gr_poly
					(pts
						(arc
							(start -0.1778 -0.2794)
							(mid -0.249642 -0.249642)
							(end -0.2794 -0.1778)
						)
						(arc
							(start -0.2794 0.1778)
							(mid -0.249642 0.249642)
							(end -0.1778 0.2794)
						)
						(arc
							(start 0.1778 0.2794)
							(mid 0.249642 0.249642)
							(end 0.2794 0.1778)
						)
						(arc
							(start 0.2794 -0.1778)
							(mid 0.249642 -0.249642)
							(end 0.1778 -0.2794)
						)
					)
					(width 0)
					(fill yes)
				)
			)
		)
		(pad "2" smd custom
			(at 0 0.4445)
			(size 0.1397 0.1397)
			(layers "F.Cu" "F.Mask" "F.Paste")
			(net "GND")
			(options
				(clearance outline)
				(anchor circle)
			)
			(primitives
				(gr_poly
					(pts
						(arc
							(start -0.1778 -0.2794)
							(mid -0.249642 -0.249642)
							(end -0.2794 -0.1778)
						)
						(arc
							(start -0.2794 0.1778)
							(mid -0.249642 0.249642)
							(end -0.1778 0.2794)
						)
						(arc
							(start 0.1778 0.2794)
							(mid 0.249642 0.249642)
							(end 0.2794 0.1778)
						)
						(arc
							(start 0.2794 -0.1778)
							(mid 0.249642 -0.249642)
							(end 0.1778 -0.2794)
						)
					)
					(width 0)
					(fill yes)
				)
			)
		)
	)
)
